(kicad_pcb
	(version 20260206)
	(generator "pcbnew")
	(generator_version "10.0")
	(general
		(thickness 1.6)
		(legacy_teardrops no)
	)
	(paper "A4")
	(title_block
		(title "v1-chassis-manager — T6M_CM_d_v01_1031_1645.brd")
		(comment 1 "Open CloudServer (Microsoft) / footprints 1224-1232 of 2512")
	)
	(layers
		(0 "F.Cu" signal "TOP")
		(4 "In1.Cu" signal "GND1")
		(6 "In2.Cu" signal "IN1")
		(8 "In3.Cu" signal "VCC1")
		(10 "In4.Cu" signal "VCC2")
		(12 "In5.Cu" signal "GND2")
		(14 "In6.Cu" signal "IN2")
		(16 "In7.Cu" signal "IN3")
		(18 "In8.Cu" signal "GND3")
		(2 "B.Cu" signal "BOTTOM")
		(9 "F.Adhes" user "F.Adhesive")
		(11 "B.Adhes" user "B.Adhesive")
		(13 "F.Paste" user "Package Geometry/Pastemask Top")
		(15 "B.Paste" user "Package Geometry/Pastemask Bottom")
		(5 "F.SilkS" user "Ref Des/Silkscreen Top")
		(7 "B.SilkS" user "Ref Des/Silkscreen Bottom")
		(1 "F.Mask" user "Board Geometry/Soldermask Top")
		(3 "B.Mask" user "Board Geometry/Soldermask Bottom")
		(17 "Dwgs.User" user "User.Drawings")
		(19 "Cmts.User" user "User.Comments")
		(21 "Eco1.User" user "User.Eco1")
		(23 "Eco2.User" user "User.Eco2")
		(25 "Edge.Cuts" user "Board Geometry/Outline")
		(27 "Margin" user)
		(31 "F.CrtYd" user "Package Geometry/Place Bound Top")
		(29 "B.CrtYd" user "Package Geometry/Place Bound Bottom")
		(35 "F.Fab" user "Ref Des/Assembly Top")
		(33 "B.Fab" user "Ref Des/Assembly Bottom")
	)
	(footprint ""
		(layer "F.Cu")
		(at 41.908222 -176.667668 180)
		(property "Reference" "Q22"
			(at 6.706362 5.85724 0)
			(unlocked yes)
			(layer "F.SilkS")
			(effects
				(font
					(size 0.7874 0.5842)
					(thickness 0.1524)
				)
				(justify left)
			)
		)
		(property "Value" ""
			(at 0 0 180)
			(layer "F.Fab")
			(effects
				(font
					(size 1.27 1.27)
				)
			)
		)
		(duplicate_pad_numbers_are_jumpers no)
		(fp_line
			(start 5.350002 4.554982)
			(end 0.649986 4.554982)
			(stroke
				(width 0.1524)
				(type default)
			)
			(layer "F.SilkS")
		)
		(fp_line
			(start 5.350002 4.3942)
			(end 5.350002 4.554982)
			(stroke
				(width 0.1524)
				(type default)
			)
			(layer "F.SilkS")
		)
		(fp_line
			(start 5.350002 -0.744982)
			(end 5.350002 -0.5842)
			(stroke
				(width 0.1524)
				(type default)
			)
			(layer "F.SilkS")
		)
		(fp_line
			(start 0.649986 4.554982)
			(end 0.649986 4.318)
			(stroke
				(width 0.1524)
				(type default)
			)
			(layer "F.SilkS")
		)
		(fp_line
			(start 0.649986 -0.5334)
			(end 0.649986 -0.744982)
			(stroke
				(width 0.1524)
				(type default)
			)
			(layer "F.SilkS")
		)
		(fp_line
			(start 0.649986 -0.744982)
			(end 5.350002 -0.744982)
			(stroke
				(width 0.1524)
				(type default)
			)
			(layer "F.SilkS")
		)
		(fp_poly
			(pts
				(xy -0.79375 -0.000762) (xy -1.83515 -0.419862) (xy -1.83515 0.380238)
			)
			(stroke
				(width 0)
				(type default)
			)
			(fill yes)
			(layer "F.SilkS")
		)
		(fp_poly
			(pts
				(xy 0.649986 4.554982) (xy 5.350002 4.554982) (xy 5.350002 4.318) (xy 6.2738 4.318) (xy 6.2738 -0.508)
				(xy 5.350002 -0.508) (xy 5.350002 -0.744982) (xy 0.649986 -0.744982) (xy 0.649986 -0.4064) (xy -0.635 -0.4064)
				(xy -0.635 4.2164) (xy 0.649986 4.2164)
			)
			(stroke
				(width 0)
				(type default)
			)
			(fill no)
			(layer "F.CrtYd")
		)
		(fp_line
			(start 5.350002 4.554982)
			(end 0.649986 4.554982)
			(stroke
				(width 0.1)
				(type default)
			)
			(layer "F.Fab")
		)
		(fp_line
			(start 5.350002 -0.744982)
			(end 5.350002 4.554982)
			(stroke
				(width 0.1)
				(type default)
			)
			(layer "F.Fab")
		)
		(fp_line
			(start 0.649986 4.554982)
			(end 0.649986 -0.744982)
			(stroke
				(width 0.1)
				(type default)
			)
			(layer "F.Fab")
		)
		(fp_line
			(start 0.649986 -0.744982)
			(end 5.350002 -0.744982)
			(stroke
				(width 0.1)
				(type default)
			)
			(layer "F.Fab")
		)
		(fp_circle
			(center 2.724912 1.905)
			(end 2.470912 1.905)
			(stroke
				(width 0.1)
				(type default)
			)
			(fill no)
			(layer "F.Fab")
		)
		(pad "1" smd rect
			(at 0 0 90)
			(size 0.7112 1.1684)
			(layers "F.Cu" "F.Mask" "F.Paste")
			(net "P12V_AUX")
		)
		(pad "2" smd rect
			(at 0 1.27 90)
			(size 0.7112 1.1684)
			(layers "F.Cu" "F.Mask" "F.Paste")
			(net "P12V_AUX")
		)
		(pad "3" smd rect
			(at 0 2.54 90)
			(size 0.7112 1.1684)
			(layers "F.Cu" "F.Mask" "F.Paste")
			(net "P12V_AUX")
		)
		(pad "4" smd rect
			(at 0 3.81 90)
			(size 0.7112 1.1684)
			(layers "F.Cu" "F.Mask" "F.Paste")
			(net "VR_HSC_NODE1_GATE")
		)
		(pad "5" smd custom
			(at 3.925062 1.905 90)
			(size 1.149985 1.149985)
			(layers "F.Cu" "F.Mask" "F.Paste")
			(net "VSENSE_HSC_NODE1")
			(options
				(clearance outline)
				(anchor circle)
			)
			(primitives
				(gr_poly
					(pts
						(xy -2.350008 -2.29997) (xy -2.350008 -0.8001) (xy -2.100072 -0.8001) (xy -2.100072 2.29997) (xy 2.100072 2.29997)
						(xy 2.100072 -0.8001) (xy 2.350008 -0.8001) (xy 2.350008 -2.29997)
					)
					(width 0)
					(fill yes)
				)
			)
		)
	)
	(footprint ""
		(layer "F.Cu")
		(at 36.34359 -104.502712 180)
		(property "Reference" "R1088"
			(at 0.802132 -3.263138 0)
			(unlocked yes)
			(layer "F.SilkS")
			(effects
				(font
					(size 0.7874 0.5842)
					(thickness 0.1524)
				)
				(justify left)
			)
		)
		(property "Value" ""
			(at 0 0 180)
			(layer "F.Fab")
			(effects
				(font
					(size 1.27 1.27)
				)
			)
		)
		(duplicate_pad_numbers_are_jumpers no)
		(fp_line
			(start 0.7874 0.4064)
			(end -0.7874 0.4064)
			(stroke
				(width 0.1524)
				(type default)
			)
			(layer "F.SilkS")
		)
		(fp_line
			(start 0.7874 -0.4064)
			(end 0.7874 0.4064)
			(stroke
				(width 0.1524)
				(type default)
			)
			(layer "F.SilkS")
		)
		(fp_line
			(start -0.7874 0.4064)
			(end -0.7874 -0.4064)
			(stroke
				(width 0.1524)
				(type default)
			)
			(layer "F.SilkS")
		)
		(fp_line
			(start -0.7874 -0.4064)
			(end 0.7874 -0.4064)
			(stroke
				(width 0.1524)
				(type default)
			)
			(layer "F.SilkS")
		)
		(fp_poly
			(pts
				(xy -0.508 0.2794) (xy -0.508 0.2286) (xy -0.635 0.2286) (xy -0.635 -0.254) (xy -0.5334 -0.254)
				(xy -0.5334 -0.2794) (xy 0.5334 -0.2794) (xy 0.5334 -0.254) (xy 0.635 -0.254) (xy 0.635 0.254) (xy 0.5334 0.254)
				(xy 0.5334 0.2794)
			)
			(stroke
				(width 0)
				(type default)
			)
			(fill no)
			(layer "F.CrtYd")
		)
		(pad "1" smd rect
			(at 0.40005 0 180)
			(size 0.4572 0.508)
			(layers "F.Cu" "F.Mask" "F.Paste")
			(net "P1V5_SUS_NODE1_ADJ")
		)
		(pad "2" smd rect
			(at -0.40005 0 180)
			(size 0.4572 0.508)
			(layers "F.Cu" "F.Mask" "F.Paste")
			(net "P1V5_SUS_NODE1")
		)
	)
	(footprint ""
		(layer "F.Cu")
		(at 82.340196 -107.097322)
		(property "Reference" "R1235"
			(at -5.44957 -0.57277 0)
			(unlocked yes)
			(layer "F.SilkS")
			(effects
				(font
					(size 0.7874 0.5842)
					(thickness 0.1524)
				)
				(justify left)
			)
		)
		(property "Value" ""
			(at 0 0 0)
			(layer "F.Fab")
			(effects
				(font
					(size 1.27 1.27)
				)
			)
		)
		(duplicate_pad_numbers_are_jumpers no)
		(fp_line
			(start -0.7874 -0.4064)
			(end 0.7874 -0.4064)
			(stroke
				(width 0.1524)
				(type default)
			)
			(layer "F.SilkS")
		)
		(fp_line
			(start -0.7874 0.4064)
			(end -0.7874 -0.4064)
			(stroke
				(width 0.1524)
				(type default)
			)
			(layer "F.SilkS")
		)
		(fp_line
			(start 0.7874 -0.4064)
			(end 0.7874 0.4064)
			(stroke
				(width 0.1524)
				(type default)
			)
			(layer "F.SilkS")
		)
		(fp_line
			(start 0.7874 0.4064)
			(end -0.7874 0.4064)
			(stroke
				(width 0.1524)
				(type default)
			)
			(layer "F.SilkS")
		)
		(fp_poly
			(pts
				(xy -0.508 0.2794) (xy -0.508 0.2286) (xy -0.635 0.2286) (xy -0.635 -0.254) (xy -0.5334 -0.254)
				(xy -0.5334 -0.2794) (xy 0.5334 -0.2794) (xy 0.5334 -0.254) (xy 0.635 -0.254) (xy 0.635 0.254) (xy 0.5334 0.254)
				(xy 0.5334 0.2794)
			)
			(stroke
				(width 0)
				(type default)
			)
			(fill no)
			(layer "F.CrtYd")
		)
		(pad "1" smd rect
			(at 0.40005 0)
			(size 0.4572 0.508)
			(layers "F.Cu" "F.Mask" "F.Paste")
			(net "GND")
		)
		(pad "2" smd rect
			(at -0.40005 0)
			(size 0.4572 0.508)
			(layers "F.Cu" "F.Mask" "F.Paste")
			(net "FM_CPLD_NODE1_P3V3_SUS_EN")
		)
	)
	(footprint ""
		(layer "F.Cu")
		(at 95.404432 -4.518406)
		(property "Reference" "C135"
			(at -1.055116 1.38557 0)
			(unlocked yes)
			(layer "F.SilkS")
			(effects
				(font
					(size 0.7874 0.5842)
					(thickness 0.1524)
				)
				(justify left)
			)
		)
		(property "Value" ""
			(at 0 0 0)
			(layer "F.Fab")
			(effects
				(font
					(size 1.27 1.27)
				)
			)
		)
		(duplicate_pad_numbers_are_jumpers no)
		(fp_line
			(start -0.7874 -0.4064)
			(end 0.7874 -0.4064)
			(stroke
				(width 0.1524)
				(type default)
			)
			(layer "F.SilkS")
		)
		(fp_line
			(start -0.7874 0.4064)
			(end -0.7874 -0.4064)
			(stroke
				(width 0.1524)
				(type default)
			)
			(layer "F.SilkS")
		)
		(fp_line
			(start 0 0.381)
			(end 0 -0.381)
			(stroke
				(width 0.1524)
				(type default)
			)
			(layer "F.SilkS")
		)
		(fp_line
			(start 0.7874 -0.4064)
			(end 0.7874 0.4064)
			(stroke
				(width 0.1524)
				(type default)
			)
			(layer "F.SilkS")
		)
		(fp_line
			(start 0.7874 0.4064)
			(end -0.7874 0.4064)
			(stroke
				(width 0.1524)
				(type default)
			)
			(layer "F.SilkS")
		)
		(fp_poly
			(pts
				(xy -0.5334 0.254) (xy -0.635 0.254) (xy -0.635 0.2286) (xy -0.635 -0.254) (xy -0.5334 -0.254) (xy -0.5334 -0.2794)
				(xy 0.5334 -0.2794) (xy 0.5334 -0.254) (xy 0.635 -0.254) (xy 0.635 0.254) (xy 0.5334 0.254) (xy 0.5334 0.2794)
				(xy -0.508 0.2794) (xy -0.5334 0.2794)
			)
			(stroke
				(width 0)
				(type default)
			)
			(fill no)
			(layer "F.CrtYd")
		)
		(pad "1" smd rect
			(at 0.40005 0)
			(size 0.4572 0.508)
			(layers "F.Cu" "F.Mask" "F.Paste")
			(net "GND")
		)
		(pad "2" smd rect
			(at -0.40005 0)
			(size 0.4572 0.508)
			(layers "F.Cu" "F.Mask" "F.Paste")
			(net "P5V_NODE1")
		)
	)
	(footprint ""
		(layer "F.Cu")
		(at 134.60476 -188.126624 90)
		(property "Reference" "C746"
			(at 4.949444 -1.209548 90)
			(unlocked yes)
			(layer "F.SilkS")
			(effects
				(font
					(size 0.7874 0.5842)
					(thickness 0.1524)
				)
				(justify left)
			)
		)
		(property "Value" ""
			(at 0 0 90)
			(layer "F.Fab")
			(effects
				(font
					(size 1.27 1.27)
				)
			)
		)
		(duplicate_pad_numbers_are_jumpers no)
		(fp_line
			(start 0.7874 -0.4064)
			(end 0.7874 0.4064)
			(stroke
				(width 0.1524)
				(type default)
			)
			(layer "F.SilkS")
		)
		(fp_line
			(start -0.7874 -0.4064)
			(end 0.7874 -0.4064)
			(stroke
				(width 0.1524)
				(type default)
			)
			(layer "F.SilkS")
		)
		(fp_line
			(start 0 0.381)
			(end 0 -0.381)
			(stroke
				(width 0.1524)
				(type default)
			)
			(layer "F.SilkS")
		)
		(fp_line
			(start 0.7874 0.4064)
			(end -0.7874 0.4064)
			(stroke
				(width 0.1524)
				(type default)
			)
			(layer "F.SilkS")
		)
		(fp_line
			(start -0.7874 0.4064)
			(end -0.7874 -0.4064)
			(stroke
				(width 0.1524)
				(type default)
			)
			(layer "F.SilkS")
		)
		(fp_poly
			(pts
				(xy -0.5334 0.254) (xy -0.635 0.254) (xy -0.635 0.2286) (xy -0.635 -0.254) (xy -0.5334 -0.254) (xy -0.5334 -0.2794)
				(xy 0.5334 -0.2794) (xy 0.5334 -0.254) (xy 0.635 -0.254) (xy 0.635 0.254) (xy 0.5334 0.254) (xy 0.5334 0.2794)
				(xy -0.508 0.2794) (xy -0.5334 0.2794)
			)
			(stroke
				(width 0)
				(type default)
			)
			(fill no)
			(layer "F.CrtYd")
		)
		(pad "1" smd rect
			(at 0.40005 0 90)
			(size 0.4572 0.508)
			(layers "F.Cu" "F.Mask" "F.Paste")
			(net "UART_T10_NODE1_TXD_R")
		)
		(pad "2" smd rect
			(at -0.40005 0 90)
			(size 0.4572 0.508)
			(layers "F.Cu" "F.Mask" "F.Paste")
			(net "GND")
		)
	)
	(footprint ""
		(layer "F.Cu")
		(at 2.693162 -155.480766 180)
		(property "Reference" "R1068"
			(at 1.343152 0.014478 90)
			(unlocked yes)
			(layer "F.SilkS")
			(effects
				(font
					(size 0.7874 0.5842)
					(thickness 0.1524)
				)
				(justify left)
			)
		)
		(property "Value" ""
			(at 0 0 180)
			(layer "F.Fab")
			(effects
				(font
					(size 1.27 1.27)
				)
			)
		)
		(duplicate_pad_numbers_are_jumpers no)
		(fp_line
			(start 0.7874 0.4064)
			(end -0.7874 0.4064)
			(stroke
				(width 0.1524)
				(type default)
			)
			(layer "F.SilkS")
		)
		(fp_line
			(start 0.7874 -0.4064)
			(end 0.7874 0.4064)
			(stroke
				(width 0.1524)
				(type default)
			)
			(layer "F.SilkS")
		)
		(fp_line
			(start -0.7874 0.4064)
			(end -0.7874 -0.4064)
			(stroke
				(width 0.1524)
				(type default)
			)
			(layer "F.SilkS")
		)
		(fp_line
			(start -0.7874 -0.4064)
			(end 0.7874 -0.4064)
			(stroke
				(width 0.1524)
				(type default)
			)
			(layer "F.SilkS")
		)
		(fp_poly
			(pts
				(xy -0.508 0.2794) (xy -0.508 0.2286) (xy -0.635 0.2286) (xy -0.635 -0.254) (xy -0.5334 -0.254)
				(xy -0.5334 -0.2794) (xy 0.5334 -0.2794) (xy 0.5334 -0.254) (xy 0.635 -0.254) (xy 0.635 0.254) (xy 0.5334 0.254)
				(xy 0.5334 0.2794)
			)
			(stroke
				(width 0)
				(type default)
			)
			(fill no)
			(layer "F.CrtYd")
		)
		(pad "1" smd rect
			(at 0.40005 0 180)
			(size 0.4572 0.508)
			(layers "F.Cu" "F.Mask" "F.Paste")
			(net "UART_RI_P5_LS_N")
		)
		(pad "2" smd rect
			(at -0.40005 0 180)
			(size 0.4572 0.508)
			(layers "F.Cu" "F.Mask" "F.Paste")
			(net "UART_RI_P5_N")
		)
	)
	(footprint ""
		(layer "F.Cu")
		(at 168.244012 -77.328776 180)
		(property "Reference" "PC22"
			(at -2.634234 -0.240538 0)
			(unlocked yes)
			(layer "F.SilkS")
			(effects
				(font
					(size 0.7874 0.5842)
					(thickness 0.1524)
				)
				(justify left)
			)
		)
		(property "Value" ""
			(at 0 0 180)
			(layer "F.Fab")
			(effects
				(font
					(size 1.27 1.27)
				)
			)
		)
		(duplicate_pad_numbers_are_jumpers no)
		(fp_line
			(start 1.905 0.8636)
			(end -1.905 0.8636)
			(stroke
				(width 0.1524)
				(type default)
			)
			(layer "F.SilkS")
		)
		(fp_line
			(start 1.905 -0.8636)
			(end 1.905 0.8636)
			(stroke
				(width 0.1524)
				(type default)
			)
			(layer "F.SilkS")
		)
		(fp_line
			(start 0 0.8382)
			(end 0 -0.8382)
			(stroke
				(width 0.1524)
				(type default)
			)
			(layer "F.SilkS")
		)
		(fp_line
			(start -1.905 0.8636)
			(end -1.905 -0.8636)
			(stroke
				(width 0.1524)
				(type default)
			)
			(layer "F.SilkS")
		)
		(fp_line
			(start -1.905 -0.8636)
			(end 1.905 -0.8636)
			(stroke
				(width 0.1524)
				(type default)
			)
			(layer "F.SilkS")
		)
		(fp_rect
			(start -1.524 0.7366)
			(end 1.524 -0.7366)
			(stroke
				(width 0)
				(type default)
			)
			(fill no)
			(layer "F.CrtYd")
		)
		(pad "1" smd rect
			(at 0.94996 0 180)
			(size 1.1176 1.3716)
			(layers "F.Cu" "F.Mask" "F.Paste")
			(net "P1V8_NODE1")
		)
		(pad "2" smd rect
			(at -0.94996 0 180)
			(size 1.1176 1.3716)
			(layers "F.Cu" "F.Mask" "F.Paste")
			(net "GND")
		)
	)
	(footprint ""
		(layer "F.Cu")
		(at 33.344104 -119.567452)
		(property "Reference" "R1117"
			(at -6.021324 0.992124 0)
			(unlocked yes)
			(layer "F.SilkS")
			(effects
				(font
					(size 0.7874 0.5842)
					(thickness 0.1524)
				)
				(justify left)
			)
		)
		(property "Value" ""
			(at 0 0 0)
			(layer "F.Fab")
			(effects
				(font
					(size 1.27 1.27)
				)
			)
		)
		(duplicate_pad_numbers_are_jumpers no)
		(fp_line
			(start -0.7874 -0.4064)
			(end 0.7874 -0.4064)
			(stroke
				(width 0.1524)
				(type default)
			)
			(layer "F.SilkS")
		)
		(fp_line
			(start -0.7874 0.4064)
			(end -0.7874 -0.4064)
			(stroke
				(width 0.1524)
				(type default)
			)
			(layer "F.SilkS")
		)
		(fp_line
			(start 0.7874 -0.4064)
			(end 0.7874 0.4064)
			(stroke
				(width 0.1524)
				(type default)
			)
			(layer "F.SilkS")
		)
		(fp_line
			(start 0.7874 0.4064)
			(end -0.7874 0.4064)
			(stroke
				(width 0.1524)
				(type default)
			)
			(layer "F.SilkS")
		)
		(fp_poly
			(pts
				(xy -0.508 0.2794) (xy -0.508 0.2286) (xy -0.635 0.2286) (xy -0.635 -0.254) (xy -0.5334 -0.254)
				(xy -0.5334 -0.2794) (xy 0.5334 -0.2794) (xy 0.5334 -0.254) (xy 0.635 -0.254) (xy 0.635 0.254) (xy 0.5334 0.254)
				(xy 0.5334 0.2794)
			)
			(stroke
				(width 0)
				(type default)
			)
			(fill no)
			(layer "F.CrtYd")
		)
		(pad "1" smd rect
			(at 0.40005 0)
			(size 0.4572 0.508)
			(layers "F.Cu" "F.Mask" "F.Paste")
			(net "FM_CPLD_NODE1_P1V5_EN_G")
		)
		(pad "2" smd rect
			(at -0.40005 0)
			(size 0.4572 0.508)
			(layers "F.Cu" "F.Mask" "F.Paste")
			(net "P3V3_STB_NODE1")
		)
	)
	(footprint ""
		(layer "F.Cu")
		(at 127.24257 -26.569416 -90)
		(property "Reference" "R1140"
			(at 5.325618 -0.028448 90)
			(unlocked yes)
			(layer "F.SilkS")
			(effects
				(font
					(size 0.7874 0.5842)
					(thickness 0.1524)
				)
				(justify left)
			)
		)
		(property "Value" ""
			(at 0 0 270)
			(layer "F.Fab")
			(effects
				(font
					(size 1.27 1.27)
				)
			)
		)
		(duplicate_pad_numbers_are_jumpers no)
		(fp_line
			(start -0.7874 0.4064)
			(end -0.7874 -0.4064)
			(stroke
				(width 0.1524)
				(type default)
			)
			(layer "F.SilkS")
		)
		(fp_line
			(start 0.7874 0.4064)
			(end -0.7874 0.4064)
			(stroke
				(width 0.1524)
				(type default)
			)
			(layer "F.SilkS")
		)
		(fp_line
			(start -0.7874 -0.4064)
			(end 0.7874 -0.4064)
			(stroke
				(width 0.1524)
				(type default)
			)
			(layer "F.SilkS")
		)
		(fp_line
			(start 0.7874 -0.4064)
			(end 0.7874 0.4064)
			(stroke
				(width 0.1524)
				(type default)
			)
			(layer "F.SilkS")
		)
		(fp_poly
			(pts
				(xy -0.508 0.2794) (xy -0.508 0.2286) (xy -0.635 0.2286) (xy -0.635 -0.254) (xy -0.5334 -0.254)
				(xy -0.5334 -0.2794) (xy 0.5334 -0.2794) (xy 0.5334 -0.254) (xy 0.635 -0.254) (xy 0.635 0.254) (xy 0.5334 0.254)
				(xy 0.5334 0.2794)
			)
			(stroke
				(width 0)
				(type default)
			)
			(fill no)
			(layer "F.CrtYd")
		)
		(pad "1" smd rect
			(at 0.40005 0 270)
			(size 0.4572 0.508)
			(layers "F.Cu" "F.Mask" "F.Paste")
			(net "P3V3_STB_NODE1")
		)
		(pad "2" smd rect
			(at -0.40005 0 270)
			(size 0.4572 0.508)
			(layers "F.Cu" "F.Mask" "F.Paste")
			(net "SIO_PIN73")
		)
	)
)
